(kicad_pcb
	(version 20260206)
	(generator "pcbnew")
	(generator_version "10.0")
	(general
		(thickness 1.6)
		(legacy_teardrops no)
	)
	(paper "A4")
	(title_block
		(title "03242023_DA0F0TMBIJ0_F0T_Motherboard_J_brd_V01_OCP.brd")
		(comment 1 "Grand Teton / footprints 112-119 of 6105")
	)
	(layers
		(0 "F.Cu" signal "TOP")
		(4 "In1.Cu" signal "GND")
		(6 "In2.Cu" signal "IN1")
		(8 "In3.Cu" signal "GND1")
		(10 "In4.Cu" signal "IN2")
		(12 "In5.Cu" signal "GND2")
		(14 "In6.Cu" signal "IN3")
		(16 "In7.Cu" signal "GND3")
		(18 "In8.Cu" signal "VCC")
		(20 "In9.Cu" signal "VCC1")
		(22 "In10.Cu" signal "GND4")
		(24 "In11.Cu" signal "IN4")
		(26 "In12.Cu" signal "GND5")
		(28 "In13.Cu" signal "IN5")
		(30 "In14.Cu" signal "GND6")
		(32 "In15.Cu" signal "IN6")
		(34 "In16.Cu" signal "GND7")
		(2 "B.Cu" signal "BOTTOM")
		(9 "F.Adhes" user "F.Adhesive")
		(11 "B.Adhes" user "B.Adhesive")
		(13 "F.Paste" user "Package Geometry/Pastemask Top")
		(15 "B.Paste" user "Package Geometry/Pastemask Bottom")
		(5 "F.SilkS" user "Ref Des/Silkscreen Top")
		(7 "B.SilkS" user "Ref Des/Silkscreen Bottom")
		(1 "F.Mask" user "Board Geometry/Soldermask Top")
		(3 "B.Mask" user "Board Geometry/Soldermask Bottom")
		(17 "Dwgs.User" user "User.Drawings")
		(19 "Cmts.User" user "User.Comments")
		(21 "Eco1.User" user "User.Eco1")
		(23 "Eco2.User" user "User.Eco2")
		(25 "Edge.Cuts" user "Board Geometry/Outline")
		(27 "Margin" user)
		(31 "F.CrtYd" user "Package Geometry/Place Bound Top")
		(29 "B.CrtYd" user "Package Geometry/Place Bound Bottom")
		(35 "F.Fab" user "Ref Des/Assembly Top")
		(33 "B.Fab" user "Ref Des/Assembly Bottom")
	)
	(footprint ""
		(layer "F.Cu")
		(at 209.743802 -125.476)
		(property "Reference" "R4808"
			(at 0 0 0)
			(layer "F.SilkS")
			(hide yes)
			(effects
				(font
					(size 1.27 1.27)
				)
			)
		)
		(property "Value" ""
			(at 0 0 0)
			(layer "F.Fab")
			(effects
				(font
					(size 1.27 1.27)
				)
			)
		)
		(duplicate_pad_numbers_are_jumpers no)
		(fp_line
			(start -0.7874 -0.4064)
			(end 0.7874 -0.4064)
			(stroke
				(width 0.1524)
				(type default)
			)
			(layer "F.SilkS")
		)
		(fp_line
			(start -0.7874 0.4064)
			(end -0.7874 -0.4064)
			(stroke
				(width 0.1524)
				(type default)
			)
			(layer "F.SilkS")
		)
		(fp_line
			(start 0.7874 -0.4064)
			(end 0.7874 0.4064)
			(stroke
				(width 0.1524)
				(type default)
			)
			(layer "F.SilkS")
		)
		(fp_line
			(start 0.7874 0.4064)
			(end -0.7874 0.4064)
			(stroke
				(width 0.1524)
				(type default)
			)
			(layer "F.SilkS")
		)
		(fp_line
			(start -0.67945 -0.305054)
			(end -0.12065 -0.305054)
			(stroke
				(width 0.1)
				(type default)
			)
			(layer "F.Fab")
		)
		(fp_line
			(start -0.67945 0.3048)
			(end -0.67945 -0.305054)
			(stroke
				(width 0.1)
				(type default)
			)
			(layer "F.Fab")
		)
		(fp_line
			(start -0.12065 -0.305054)
			(end -0.12065 -0.2794)
			(stroke
				(width 0.1)
				(type default)
			)
			(layer "F.Fab")
		)
		(fp_line
			(start -0.12065 -0.2794)
			(end 0.12065 -0.2794)
			(stroke
				(width 0.1)
				(type default)
			)
			(layer "F.Fab")
		)
		(fp_line
			(start -0.12065 0.2794)
			(end -0.12065 0.3048)
			(stroke
				(width 0.1)
				(type default)
			)
			(layer "F.Fab")
		)
		(fp_line
			(start -0.12065 0.3048)
			(end -0.67945 0.3048)
			(stroke
				(width 0.1)
				(type default)
			)
			(layer "F.Fab")
		)
		(fp_line
			(start 0.120396 0.2794)
			(end -0.12065 0.2794)
			(stroke
				(width 0.1)
				(type default)
			)
			(layer "F.Fab")
		)
		(fp_line
			(start 0.120396 0.3048)
			(end 0.120396 0.2794)
			(stroke
				(width 0.1)
				(type default)
			)
			(layer "F.Fab")
		)
		(fp_line
			(start 0.12065 -0.3048)
			(end 0.67945 -0.3048)
			(stroke
				(width 0.1)
				(type default)
			)
			(layer "F.Fab")
		)
		(fp_line
			(start 0.12065 -0.2794)
			(end 0.12065 -0.3048)
			(stroke
				(width 0.1)
				(type default)
			)
			(layer "F.Fab")
		)
		(fp_line
			(start 0.67945 -0.3048)
			(end 0.67945 0.3048)
			(stroke
				(width 0.1)
				(type default)
			)
			(layer "F.Fab")
		)
		(fp_line
			(start 0.67945 0.3048)
			(end 0.120396 0.3048)
			(stroke
				(width 0.1)
				(type default)
			)
			(layer "F.Fab")
		)
		(pad "1" smd circle
			(at -0.40005 0)
			(size 0 0)
			(layers "F.Cu" "F.Mask" "F.Paste")
			(net "PWRGD_DSW_PWROK")
		)
		(pad "2" smd circle
			(at 0.40005 0)
			(size 0 0)
			(layers "F.Cu" "F.Mask" "F.Paste")
			(net "GND")
		)
	)
	(footprint ""
		(layer "F.Cu")
		(at 20.802346 -161.06394 90)
		(property "Reference" "PJ48"
			(at -2.825242 -1.264666 0)
			(unlocked yes)
			(layer "F.SilkS")
			(effects
				(font
					(size 0.7874 0.5842)
					(thickness 0.1524)
				)
				(justify left)
			)
		)
		(property "Value" ""
			(at 0 0 90)
			(layer "F.Fab")
			(effects
				(font
					(size 1.27 1.27)
				)
			)
		)
		(duplicate_pad_numbers_are_jumpers no)
		(pad "1" smd circle
			(at -0.7493 0 180)
			(size 0 0)
			(layers "F.Cu" "F.Mask" "F.Paste")
			(net "VSENSE_PVCCD_HV_CPU1_DP")
		)
		(pad "2" smd rect
			(at 0.7493 0)
			(size 0.7112 0.8128)
			(layers "F.Cu" "F.Mask" "F.Paste")
			(net "SH_PVCCD_HV_CPU1")
		)
		(zone
			(layer "F.Cu")
			(hatch none 0.5)
			(connect_pads
				(clearance 0)
			)
			(min_thickness 0.25)
			(keepout
				(tracks allowed)
				(vias not_allowed)
				(pads allowed)
				(copperpour not_allowed)
				(footprints allowed)
			)
			(placement
				(enabled no)
				(sheetname "")
			)
			(fill
				(thermal_gap 0.5)
				(thermal_bridge_width 0.5)
				(island_removal_mode 0)
			)
			(polygon
				(pts
					(xy 20.395946 -159.88284) (xy 21.213572 -159.88284) (xy 21.213572 -162.27044) (xy 20.395946 -162.27044)
				)
			)
		)
	)
	(footprint ""
		(layer "F.Cu")
		(at 32.780478 -439.720228)
		(property "Reference" "R3108"
			(at 0 0 0)
			(layer "F.SilkS")
			(hide yes)
			(effects
				(font
					(size 1.27 1.27)
				)
			)
		)
		(property "Value" ""
			(at 0 0 0)
			(layer "F.Fab")
			(effects
				(font
					(size 1.27 1.27)
				)
			)
		)
		(duplicate_pad_numbers_are_jumpers no)
		(fp_line
			(start -0.7874 -0.4064)
			(end 0.7874 -0.4064)
			(stroke
				(width 0.1524)
				(type default)
			)
			(layer "F.SilkS")
		)
		(fp_line
			(start -0.7874 0.4064)
			(end -0.7874 -0.4064)
			(stroke
				(width 0.1524)
				(type default)
			)
			(layer "F.SilkS")
		)
		(fp_line
			(start 0.7874 -0.4064)
			(end 0.7874 0.4064)
			(stroke
				(width 0.1524)
				(type default)
			)
			(layer "F.SilkS")
		)
		(fp_line
			(start 0.7874 0.4064)
			(end -0.7874 0.4064)
			(stroke
				(width 0.1524)
				(type default)
			)
			(layer "F.SilkS")
		)
		(fp_line
			(start -0.67945 -0.305054)
			(end -0.12065 -0.305054)
			(stroke
				(width 0.1)
				(type default)
			)
			(layer "F.Fab")
		)
		(fp_line
			(start -0.67945 0.3048)
			(end -0.67945 -0.305054)
			(stroke
				(width 0.1)
				(type default)
			)
			(layer "F.Fab")
		)
		(fp_line
			(start -0.12065 -0.305054)
			(end -0.12065 -0.2794)
			(stroke
				(width 0.1)
				(type default)
			)
			(layer "F.Fab")
		)
		(fp_line
			(start -0.12065 -0.2794)
			(end 0.12065 -0.2794)
			(stroke
				(width 0.1)
				(type default)
			)
			(layer "F.Fab")
		)
		(fp_line
			(start -0.12065 0.2794)
			(end -0.12065 0.3048)
			(stroke
				(width 0.1)
				(type default)
			)
			(layer "F.Fab")
		)
		(fp_line
			(start -0.12065 0.3048)
			(end -0.67945 0.3048)
			(stroke
				(width 0.1)
				(type default)
			)
			(layer "F.Fab")
		)
		(fp_line
			(start 0.120396 0.2794)
			(end -0.12065 0.2794)
			(stroke
				(width 0.1)
				(type default)
			)
			(layer "F.Fab")
		)
		(fp_line
			(start 0.120396 0.3048)
			(end 0.120396 0.2794)
			(stroke
				(width 0.1)
				(type default)
			)
			(layer "F.Fab")
		)
		(fp_line
			(start 0.12065 -0.3048)
			(end 0.67945 -0.3048)
			(stroke
				(width 0.1)
				(type default)
			)
			(layer "F.Fab")
		)
		(fp_line
			(start 0.12065 -0.2794)
			(end 0.12065 -0.3048)
			(stroke
				(width 0.1)
				(type default)
			)
			(layer "F.Fab")
		)
		(fp_line
			(start 0.67945 -0.3048)
			(end 0.67945 0.3048)
			(stroke
				(width 0.1)
				(type default)
			)
			(layer "F.Fab")
		)
		(fp_line
			(start 0.67945 0.3048)
			(end 0.120396 0.3048)
			(stroke
				(width 0.1)
				(type default)
			)
			(layer "F.Fab")
		)
		(pad "1" smd circle
			(at -0.40005 0)
			(size 0 0)
			(layers "F.Cu" "F.Mask" "F.Paste")
			(net "SMB_2_BMC_GPU_SDA")
		)
		(pad "2" smd circle
			(at 0.40005 0)
			(size 0 0)
			(layers "F.Cu" "F.Mask" "F.Paste")
			(net "SMB_2_BMC_GPU_R_SDA")
		)
	)
	(footprint ""
		(layer "F.Cu")
		(at 119.508016 -249.320558 -90)
		(property "Reference" "C234"
			(at 0 0 270)
			(layer "F.SilkS")
			(hide yes)
			(effects
				(font
					(size 1.27 1.27)
				)
			)
		)
		(property "Value" ""
			(at 0 0 270)
			(layer "F.Fab")
			(effects
				(font
					(size 1.27 1.27)
				)
			)
		)
		(duplicate_pad_numbers_are_jumpers no)
		(fp_line
			(start -0.7874 0.4064)
			(end -0.7874 -0.4064)
			(stroke
				(width 0.1524)
				(type default)
			)
			(layer "F.SilkS")
		)
		(fp_line
			(start 0.7874 0.4064)
			(end -0.7874 0.4064)
			(stroke
				(width 0.1524)
				(type default)
			)
			(layer "F.SilkS")
		)
		(fp_line
			(start -0.7874 -0.4064)
			(end 0.7874 -0.4064)
			(stroke
				(width 0.1524)
				(type default)
			)
			(layer "F.SilkS")
		)
		(fp_line
			(start 0.7874 -0.4064)
			(end 0.7874 0.4064)
			(stroke
				(width 0.1524)
				(type default)
			)
			(layer "F.SilkS")
		)
		(fp_line
			(start -0.67945 0.3048)
			(end -0.67945 -0.305054)
			(stroke
				(width 0.1)
				(type default)
			)
			(layer "F.Fab")
		)
		(fp_line
			(start -0.12065 0.3048)
			(end -0.67945 0.3048)
			(stroke
				(width 0.1)
				(type default)
			)
			(layer "F.Fab")
		)
		(fp_line
			(start 0.120396 0.3048)
			(end 0.120396 0.2794)
			(stroke
				(width 0.1)
				(type default)
			)
			(layer "F.Fab")
		)
		(fp_line
			(start 0.67945 0.3048)
			(end 0.120396 0.3048)
			(stroke
				(width 0.1)
				(type default)
			)
			(layer "F.Fab")
		)
		(fp_line
			(start -0.12065 0.2794)
			(end -0.12065 0.3048)
			(stroke
				(width 0.1)
				(type default)
			)
			(layer "F.Fab")
		)
		(fp_line
			(start 0.120396 0.2794)
			(end -0.12065 0.2794)
			(stroke
				(width 0.1)
				(type default)
			)
			(layer "F.Fab")
		)
		(fp_line
			(start -0.12065 -0.2794)
			(end 0.12065 -0.2794)
			(stroke
				(width 0.1)
				(type default)
			)
			(layer "F.Fab")
		)
		(fp_line
			(start 0.12065 -0.2794)
			(end 0.12065 -0.3048)
			(stroke
				(width 0.1)
				(type default)
			)
			(layer "F.Fab")
		)
		(fp_line
			(start 0.12065 -0.3048)
			(end 0.67945 -0.3048)
			(stroke
				(width 0.1)
				(type default)
			)
			(layer "F.Fab")
		)
		(fp_line
			(start 0.67945 -0.3048)
			(end 0.67945 0.3048)
			(stroke
				(width 0.1)
				(type default)
			)
			(layer "F.Fab")
		)
		(fp_line
			(start -0.67945 -0.305054)
			(end -0.12065 -0.305054)
			(stroke
				(width 0.1)
				(type default)
			)
			(layer "F.Fab")
		)
		(fp_line
			(start -0.12065 -0.305054)
			(end -0.12065 -0.2794)
			(stroke
				(width 0.1)
				(type default)
			)
			(layer "F.Fab")
		)
		(pad "1" smd circle
			(at -0.40005 0 270)
			(size 0 0)
			(layers "F.Cu" "F.Mask" "F.Paste")
			(net "PVCCIN_CPU1")
		)
		(pad "2" smd circle
			(at 0.40005 0 270)
			(size 0 0)
			(layers "F.Cu" "F.Mask" "F.Paste")
			(net "GND")
		)
	)
	(footprint ""
		(layer "F.Cu")
		(at 100.820728 -355.257862 180)
		(property "Reference" "R2555"
			(at 0 0 180)
			(layer "F.SilkS")
			(hide yes)
			(effects
				(font
					(size 1.27 1.27)
				)
			)
		)
		(property "Value" ""
			(at 0 0 180)
			(layer "F.Fab")
			(effects
				(font
					(size 1.27 1.27)
				)
			)
		)
		(duplicate_pad_numbers_are_jumpers no)
		(fp_line
			(start 0.7874 0.4064)
			(end -0.7874 0.4064)
			(stroke
				(width 0.1524)
				(type default)
			)
			(layer "F.SilkS")
		)
		(fp_line
			(start 0.7874 -0.4064)
			(end 0.7874 0.4064)
			(stroke
				(width 0.1524)
				(type default)
			)
			(layer "F.SilkS")
		)
		(fp_line
			(start -0.7874 0.4064)
			(end -0.7874 -0.4064)
			(stroke
				(width 0.1524)
				(type default)
			)
			(layer "F.SilkS")
		)
		(fp_line
			(start -0.7874 -0.4064)
			(end 0.7874 -0.4064)
			(stroke
				(width 0.1524)
				(type default)
			)
			(layer "F.SilkS")
		)
		(fp_line
			(start 0.67945 0.3048)
			(end 0.120396 0.3048)
			(stroke
				(width 0.1)
				(type default)
			)
			(layer "F.Fab")
		)
		(fp_line
			(start 0.67945 -0.3048)
			(end 0.67945 0.3048)
			(stroke
				(width 0.1)
				(type default)
			)
			(layer "F.Fab")
		)
		(fp_line
			(start 0.12065 -0.2794)
			(end 0.12065 -0.3048)
			(stroke
				(width 0.1)
				(type default)
			)
			(layer "F.Fab")
		)
		(fp_line
			(start 0.12065 -0.3048)
			(end 0.67945 -0.3048)
			(stroke
				(width 0.1)
				(type default)
			)
			(layer "F.Fab")
		)
		(fp_line
			(start 0.120396 0.3048)
			(end 0.120396 0.2794)
			(stroke
				(width 0.1)
				(type default)
			)
			(layer "F.Fab")
		)
		(fp_line
			(start 0.120396 0.2794)
			(end -0.12065 0.2794)
			(stroke
				(width 0.1)
				(type default)
			)
			(layer "F.Fab")
		)
		(fp_line
			(start -0.12065 0.3048)
			(end -0.67945 0.3048)
			(stroke
				(width 0.1)
				(type default)
			)
			(layer "F.Fab")
		)
		(fp_line
			(start -0.12065 0.2794)
			(end -0.12065 0.3048)
			(stroke
				(width 0.1)
				(type default)
			)
			(layer "F.Fab")
		)
		(fp_line
			(start -0.12065 -0.2794)
			(end 0.12065 -0.2794)
			(stroke
				(width 0.1)
				(type default)
			)
			(layer "F.Fab")
		)
		(fp_line
			(start -0.12065 -0.305054)
			(end -0.12065 -0.2794)
			(stroke
				(width 0.1)
				(type default)
			)
			(layer "F.Fab")
		)
		(fp_line
			(start -0.67945 0.3048)
			(end -0.67945 -0.305054)
			(stroke
				(width 0.1)
				(type default)
			)
			(layer "F.Fab")
		)
		(fp_line
			(start -0.67945 -0.305054)
			(end -0.12065 -0.305054)
			(stroke
				(width 0.1)
				(type default)
			)
			(layer "F.Fab")
		)
		(pad "1" smd circle
			(at -0.40005 0 180)
			(size 0 0)
			(layers "F.Cu" "F.Mask" "F.Paste")
			(net "SVID_ALERT0_CPU1_R_N")
		)
		(pad "2" smd circle
			(at 0.40005 0 180)
			(size 0 0)
			(layers "F.Cu" "F.Mask" "F.Paste")
			(net "PVNN_TERM_CPU1")
		)
	)
	(footprint ""
		(layer "F.Cu")
		(at 154.739594 -402.371052 -90)
		(property "Reference" "C764"
			(at 0 0 270)
			(layer "F.SilkS")
			(hide yes)
			(effects
				(font
					(size 1.27 1.27)
				)
			)
		)
		(property "Value" ""
			(at 0 0 270)
			(layer "F.Fab")
			(effects
				(font
					(size 1.27 1.27)
				)
			)
		)
		(duplicate_pad_numbers_are_jumpers no)
		(fp_line
			(start -0.299974 0.150114)
			(end -0.299974 -0.150114)
			(stroke
				(width 0.1)
				(type default)
			)
			(layer "F.Fab")
		)
		(fp_line
			(start 0.299974 0.150114)
			(end -0.299974 0.150114)
			(stroke
				(width 0.1)
				(type default)
			)
			(layer "F.Fab")
		)
		(fp_line
			(start -0.299974 -0.150114)
			(end 0.299974 -0.150114)
			(stroke
				(width 0.1)
				(type default)
			)
			(layer "F.Fab")
		)
		(fp_line
			(start 0.299974 -0.150114)
			(end 0.299974 0.150114)
			(stroke
				(width 0.1)
				(type default)
			)
			(layer "F.Fab")
		)
		(pad "1" smd rect
			(at -0.2667 0 270)
			(size 0.3048 0.381)
			(layers "F.Cu" "F.Mask" "F.Paste")
			(net "P5E_CPU1_PE2_TX_C_DN<4>")
		)
		(pad "2" smd rect
			(at 0.2667 0 270)
			(size 0.3048 0.381)
			(layers "F.Cu" "F.Mask" "F.Paste")
			(net "P5E_CPU1_PE2_TX_DN<4>")
		)
	)
	(footprint ""
		(layer "F.Cu")
		(at 100.936806 -102.693216)
		(property "Reference" "Q79"
			(at 1.7399 -0.815848 0)
			(unlocked yes)
			(layer "F.SilkS")
			(effects
				(font
					(size 0.7874 0.5842)
					(thickness 0.1524)
				)
				(justify left)
			)
		)
		(property "Value" ""
			(at 0 0 0)
			(layer "F.Fab")
			(effects
				(font
					(size 1.27 1.27)
				)
			)
		)
		(duplicate_pad_numbers_are_jumpers no)
		(fp_line
			(start -1.332738 -1.100074)
			(end -0.4826 -1.100074)
			(stroke
				(width 0.1524)
				(type default)
			)
			(layer "F.SilkS")
		)
		(fp_line
			(start -1.332738 1.100074)
			(end -1.332738 -1.100074)
			(stroke
				(width 0.1524)
				(type default)
			)
			(layer "F.SilkS")
		)
		(fp_line
			(start -0.4826 -1.100074)
			(end 0 -0.541274)
			(stroke
				(width 0.1524)
				(type default)
			)
			(layer "F.SilkS")
		)
		(fp_line
			(start 0 -0.541274)
			(end 0.4826 -1.100074)
			(stroke
				(width 0.1524)
				(type default)
			)
			(layer "F.SilkS")
		)
		(fp_line
			(start 0.4826 -1.100074)
			(end 1.332738 -1.100074)
			(stroke
				(width 0.1524)
				(type default)
			)
			(layer "F.SilkS")
		)
		(fp_line
			(start 1.332738 -1.100074)
			(end 1.332738 1.100074)
			(stroke
				(width 0.1524)
				(type default)
			)
			(layer "F.SilkS")
		)
		(fp_line
			(start 1.332738 1.100074)
			(end -1.332738 1.100074)
			(stroke
				(width 0.1524)
				(type default)
			)
			(layer "F.SilkS")
		)
		(fp_poly
			(pts
				(xy -0.603504 -1.950466) (xy -0.954532 -1.24841) (xy -1.30556 -1.950466)
			)
			(stroke
				(width 0)
				(type default)
			)
			(fill yes)
			(layer "F.SilkS")
		)
		(fp_line
			(start -0.674878 -1.100074)
			(end 0.674878 -1.100074)
			(stroke
				(width 0.1)
				(type default)
			)
			(layer "F.Fab")
		)
		(fp_line
			(start -0.674878 1.100074)
			(end -0.674878 -1.100074)
			(stroke
				(width 0.1)
				(type default)
			)
			(layer "F.Fab")
		)
		(fp_line
			(start 0.674878 -1.100074)
			(end 0.674878 1.100074)
			(stroke
				(width 0.1)
				(type default)
			)
			(layer "F.Fab")
		)
		(fp_line
			(start 0.674878 1.100074)
			(end -0.674878 1.100074)
			(stroke
				(width 0.1)
				(type default)
			)
			(layer "F.Fab")
		)
		(fp_poly
			(pts
				(xy -2.2352 -0.298958) (xy -2.2352 -1.001014) (xy -1.533144 -0.649986)
			)
			(stroke
				(width 0)
				(type default)
			)
			(fill yes)
			(layer "F.Fab")
		)
		(pad "1" smd rect
			(at -0.94996 -0.649986 90)
			(size 0.4318 0.508)
			(layers "F.Cu" "F.Mask" "F.Paste")
			(net "GND")
		)
		(pad "2" smd rect
			(at -0.94996 0 90)
			(size 0.4318 0.508)
			(layers "F.Cu" "F.Mask" "F.Paste")
			(net "PWRGD_PVCCD_HV_CPU0")
		)
		(pad "3" smd rect
			(at -0.94996 0.649986 90)
			(size 0.4318 0.508)
			(layers "F.Cu" "F.Mask" "F.Paste")
			(net "LED_PWRGD_PVPP_HBM_CPU0_D")
		)
		(pad "4" smd rect
			(at 0.94996 0.649986 90)
			(size 0.4318 0.508)
			(layers "F.Cu" "F.Mask" "F.Paste")
			(net "GND")
		)
		(pad "5" smd rect
			(at 0.94996 0 90)
			(size 0.4318 0.508)
			(layers "F.Cu" "F.Mask" "F.Paste")
			(net "PWRGD_PVPP_HBM_CPU0")
		)
		(pad "6" smd rect
			(at 0.94996 -0.649986 90)
			(size 0.4318 0.508)
			(layers "F.Cu" "F.Mask" "F.Paste")
			(net "LED_PWRGD_PVCCD_HV_CPU0_D")
		)
	)
	(footprint ""
		(layer "F.Cu")
		(at 350.817688 -402.371052 -90)
		(property "Reference" "C1549"
			(at 0 0 270)
			(layer "F.SilkS")
			(hide yes)
			(effects
				(font
					(size 1.27 1.27)
				)
			)
		)
		(property "Value" ""
			(at 0 0 270)
			(layer "F.Fab")
			(effects
				(font
					(size 1.27 1.27)
				)
			)
		)
		(duplicate_pad_numbers_are_jumpers no)
		(fp_line
			(start -0.299974 0.150114)
			(end -0.299974 -0.150114)
			(stroke
				(width 0.1)
				(type default)
			)
			(layer "F.Fab")
		)
		(fp_line
			(start 0.299974 0.150114)
			(end -0.299974 0.150114)
			(stroke
				(width 0.1)
				(type default)
			)
			(layer "F.Fab")
		)
		(fp_line
			(start -0.299974 -0.150114)
			(end 0.299974 -0.150114)
			(stroke
				(width 0.1)
				(type default)
			)
			(layer "F.Fab")
		)
		(fp_line
			(start 0.299974 -0.150114)
			(end 0.299974 0.150114)
			(stroke
				(width 0.1)
				(type default)
			)
			(layer "F.Fab")
		)
		(pad "1" smd rect
			(at -0.2667 0 270)
			(size 0.3048 0.381)
			(layers "F.Cu" "F.Mask" "F.Paste")
			(net "P5E_CPU0_PE4_TX_C_DP<15>")
		)
		(pad "2" smd rect
			(at 0.2667 0 270)
			(size 0.3048 0.381)
			(layers "F.Cu" "F.Mask" "F.Paste")
			(net "P5E_CPU0_PE4_TX_DP<15>")
		)
	)
)
